# T6G (Grand Teton) — schematic netlist excerpt (pin names and nets, part order shuffled) for the footprints in the layout excerpt that follows; sources: Cadence DE-HDL packaged netlist, KiCad conversion of 04192023_DAF0TMB3IC0_F0TG_MB_C_brd_V02_OCP.brd

PC154_6  Q_CAP  1UF 25V 10% X6S  pkg C0402  page 196 : A = SW_P12V_AUX_PVDDCR_CPU0_P0_FLT ; B = GND

PL68  Q_INDUCTOR4P_14  150NH IND  pkg L_TLM117513Q-151QL_11X7-5XA  page 223
  \1\  = SW_PVDDIO_P1_SW3
  \2\  = IND_PVDDIO_P1_CPL4
  \3\  = IND_PVDDIO_P1_CPL3
  \4\  = PVDDIO_P1

(kicad_pcb
	(version 20260206)
	(generator "pcbnew")
	(generator_version "10.0")
	(general
		(thickness 1.6)
		(legacy_teardrops no)
	)
	(paper "A4")
	(title_block
		(title "04192023_DAF0TMB3IC0_F0TG_MB_C_brd_V02_OCP.brd")
		(comment 1 "Grand Teton / footprints 970-971 of 8354")
	)
	(layers
		(0 "F.Cu" signal "TOP")
		(4 "In1.Cu" signal "GND")
		(6 "In2.Cu" signal "IN1")
		(8 "In3.Cu" signal "GND1")
		(10 "In4.Cu" signal "IN2")
		(12 "In5.Cu" signal "GND2")
		(14 "In6.Cu" signal "IN3")
		(16 "In7.Cu" signal "GND3")
		(18 "In8.Cu" signal "VCC")
		(20 "In9.Cu" signal "VCC1")
		(22 "In10.Cu" signal "GND4")
		(24 "In11.Cu" signal "IN4")
		(26 "In12.Cu" signal "GND5")
		(28 "In13.Cu" signal "IN5")
		(30 "In14.Cu" signal "GND6")
		(32 "In15.Cu" signal "IN6")
		(34 "In16.Cu" signal "GND7")
		(2 "B.Cu" signal "BOTTOM")
		(9 "F.Adhes" user "F.Adhesive")
		(11 "B.Adhes" user "B.Adhesive")
		(13 "F.Paste" user "Package Geometry/Pastemask Top")
		(15 "B.Paste" user "Package Geometry/Pastemask Bottom")
		(5 "F.SilkS" user "Ref Des/Silkscreen Top")
		(7 "B.SilkS" user "Ref Des/Silkscreen Bottom")
		(1 "F.Mask" user "Board Geometry/Soldermask Top")
		(3 "B.Mask" user "Board Geometry/Soldermask Bottom")
		(17 "Dwgs.User" user "User.Drawings")
		(19 "Cmts.User" user "User.Comments")
		(21 "Eco1.User" user "User.Eco1")
		(23 "Eco2.User" user "User.Eco2")
		(25 "Edge.Cuts" user "Board Geometry/Outline")
		(27 "Margin" user)
		(31 "F.CrtYd" user "Package Geometry/Place Bound Top")
		(29 "B.CrtYd" user "Package Geometry/Place Bound Bottom")
		(35 "F.Fab" user "Ref Des/Assembly Top")
		(33 "B.Fab" user "Ref Des/Assembly Bottom")
	)
	(footprint ""
		(layer "F.Cu")
		(at 344.067638 -161.056574 90)
		(property "Reference" "PC154_6"
			(at 0 0 90)
			(layer "F.SilkS")
			(hide yes)
			(effects
				(font
					(size 1.27 1.27)
				)
			)
		)
		(property "Value" ""
			(at 0 0 90)
			(layer "F.Fab")
			(effects
				(font
					(size 1.27 1.27)
				)
			)
		)
		(duplicate_pad_numbers_are_jumpers no)
		(fp_line
			(start 0.7874 -0.4064)
			(end 0.7874 0.4064)
			(stroke
				(width 0.1524)
				(type default)
			)
			(layer "F.SilkS")
		)
		(fp_line
			(start -0.7874 -0.4064)
			(end 0.7874 -0.4064)
			(stroke
				(width 0.1524)
				(type default)
			)
			(layer "F.SilkS")
		)
		(fp_line
			(start 0.7874 0.4064)
			(end -0.7874 0.4064)
			(stroke
				(width 0.1524)
				(type default)
			)
			(layer "F.SilkS")
		)
		(fp_line
			(start -0.7874 0.4064)
			(end -0.7874 -0.4064)
			(stroke
				(width 0.1524)
				(type default)
			)
			(layer "F.SilkS")
		)
		(fp_line
			(start -0.12065 -0.305054)
			(end -0.12065 -0.2794)
			(stroke
				(width 0.1)
				(type default)
			)
			(layer "F.Fab")
		)
		(fp_line
			(start -0.67945 -0.305054)
			(end -0.12065 -0.305054)
			(stroke
				(width 0.1)
				(type default)
			)
			(layer "F.Fab")
		)
		(fp_line
			(start 0.67945 -0.3048)
			(end 0.67945 0.3048)
			(stroke
				(width 0.1)
				(type default)
			)
			(layer "F.Fab")
		)
		(fp_line
			(start 0.12065 -0.3048)
			(end 0.67945 -0.3048)
			(stroke
				(width 0.1)
				(type default)
			)
			(layer "F.Fab")
		)
		(fp_line
			(start 0.12065 -0.2794)
			(end 0.12065 -0.3048)
			(stroke
				(width 0.1)
				(type default)
			)
			(layer "F.Fab")
		)
		(fp_line
			(start -0.12065 -0.2794)
			(end 0.12065 -0.2794)
			(stroke
				(width 0.1)
				(type default)
			)
			(layer "F.Fab")
		)
		(fp_line
			(start 0.120396 0.2794)
			(end -0.12065 0.2794)
			(stroke
				(width 0.1)
				(type default)
			)
			(layer "F.Fab")
		)
		(fp_line
			(start -0.12065 0.2794)
			(end -0.12065 0.3048)
			(stroke
				(width 0.1)
				(type default)
			)
			(layer "F.Fab")
		)
		(fp_line
			(start 0.67945 0.3048)
			(end 0.120396 0.3048)
			(stroke
				(width 0.1)
				(type default)
			)
			(layer "F.Fab")
		)
		(fp_line
			(start 0.120396 0.3048)
			(end 0.120396 0.2794)
			(stroke
				(width 0.1)
				(type default)
			)
			(layer "F.Fab")
		)
		(fp_line
			(start -0.12065 0.3048)
			(end -0.67945 0.3048)
			(stroke
				(width 0.1)
				(type default)
			)
			(layer "F.Fab")
		)
		(fp_line
			(start -0.67945 0.3048)
			(end -0.67945 -0.305054)
			(stroke
				(width 0.1)
				(type default)
			)
			(layer "F.Fab")
		)
		(pad "1" smd circle
			(at -0.40005 0 90)
			(size 0 0)
			(layers "F.Cu" "F.Mask" "F.Paste")
			(net "SW_P12V_AUX_PVDDCR_CPU0_P0_FLT")
		)
		(pad "2" smd circle
			(at 0.40005 0 90)
			(size 0 0)
			(layers "F.Cu" "F.Mask" "F.Paste")
			(net "GND")
		)
	)
	(footprint ""
		(layer "F.Cu")
		(at 36.99891 -337.403948)
		(property "Reference" "PL68"
			(at -3.115056 -15.887446 0)
			(unlocked yes)
			(layer "F.SilkS")
			(effects
				(font
					(size 0.7874 0.5842)
					(thickness 0.1524)
				)
				(justify left)
			)
		)
		(property "Value" ""
			(at 0 0 0)
			(layer "F.Fab")
			(effects
				(font
					(size 1.27 1.27)
				)
			)
		)
		(duplicate_pad_numbers_are_jumpers no)
		(fp_line
			(start -3.750056 -5.500116)
			(end -2.393442 -5.500116)
			(stroke
				(width 0.1524)
				(type default)
			)
			(layer "F.SilkS")
		)
		(fp_line
			(start -3.750056 5.500116)
			(end -3.750056 -5.500116)
			(stroke
				(width 0.1524)
				(type default)
			)
			(layer "F.SilkS")
		)
		(fp_line
			(start -2.393442 5.500116)
			(end -3.750056 5.500116)
			(stroke
				(width 0.1524)
				(type default)
			)
			(layer "F.SilkS")
		)
		(fp_line
			(start 2.393442 5.500116)
			(end 3.750056 5.500116)
			(stroke
				(width 0.1524)
				(type default)
			)
			(layer "F.SilkS")
		)
		(fp_line
			(start 3.750056 -5.500116)
			(end 2.393442 -5.500116)
			(stroke
				(width 0.1524)
				(type default)
			)
			(layer "F.SilkS")
		)
		(fp_line
			(start 3.750056 5.500116)
			(end 3.750056 -5.500116)
			(stroke
				(width 0.1524)
				(type default)
			)
			(layer "F.SilkS")
		)
		(fp_poly
			(pts
				(xy -3.9116 -4.249928) (xy -4.35991 -4.0259) (xy -4.35991 -4.473956)
			)
			(stroke
				(width 0)
				(type default)
			)
			(fill yes)
			(layer "F.SilkS")
		)
		(fp_line
			(start -3.750056 -5.500116)
			(end -3.750056 5.500116)
			(stroke
				(width 0.1)
				(type default)
			)
			(layer "F.Fab")
		)
		(fp_line
			(start -3.750056 5.500116)
			(end 3.750056 5.500116)
			(stroke
				(width 0.1)
				(type default)
			)
			(layer "F.Fab")
		)
		(fp_line
			(start 3.750056 -5.500116)
			(end -3.750056 -5.500116)
			(stroke
				(width 0.1)
				(type default)
			)
			(layer "F.Fab")
		)
		(fp_line
			(start 3.750056 5.500116)
			(end 3.750056 -5.500116)
			(stroke
				(width 0.1)
				(type default)
			)
			(layer "F.Fab")
		)
		(fp_poly
			(pts
				(xy -4.9276 -4.757928) (xy -4.9276 -3.741928) (xy -3.9116 -4.249928)
			)
			(stroke
				(width 0)
				(type default)
			)
			(fill yes)
			(layer "F.Fab")
		)
		(pad "1" smd rect
			(at 0 -4.249928 270)
			(size 2.413 4.5212)
			(layers "F.Cu" "F.Mask" "F.Paste")
			(net "SW_PVDDIO_P1_SW3")
		)
		(pad "2" smd rect
			(at 0 -1.175004 270)
			(size 1.3716 4.5212)
			(layers "F.Cu" "F.Mask" "F.Paste")
			(net "IND_PVDDIO_P1_CPL4")
		)
		(pad "3" smd rect
			(at 0 1.175004 270)
			(size 1.3716 4.5212)
			(layers "F.Cu" "F.Mask" "F.Paste")
			(net "IND_PVDDIO_P1_CPL3")
		)
		(pad "4" smd rect
			(at 0 4.249928 270)
			(size 2.413 4.5212)
			(layers "F.Cu" "F.Mask" "F.Paste")
			(net "PVDDIO_P1")
		)
	)
)
